(kicad_pcb
	(version 20260206)
	(generator "pcbnew")
	(generator_version "10.0")
	(general
		(thickness 1.6)
		(legacy_teardrops no)
	)
	(paper "A4")
	(title_block
		(title "Bryce Canyon_IOM_IOC_16318-2_OCP.brd")
		(comment 1 "Bryce Canyon / footprints 307-315 of 1605")
	)
	(layers
		(0 "F.Cu" signal "TOP")
		(4 "In1.Cu" signal "L2GND")
		(6 "In2.Cu" signal "L3")
		(8 "In3.Cu" signal "L4VCC")
		(10 "In4.Cu" signal "L5VCC")
		(12 "In5.Cu" signal "L6")
		(14 "In6.Cu" signal "L7GND")
		(2 "B.Cu" signal "BOTTOM")
		(9 "F.Adhes" user "F.Adhesive")
		(11 "B.Adhes" user "B.Adhesive")
		(13 "F.Paste" user "Package Geometry/Pastemask Top")
		(15 "B.Paste" user "Package Geometry/Pastemask Bottom")
		(5 "F.SilkS" user "Ref Des/Silkscreen Top")
		(7 "B.SilkS" user "Ref Des/Silkscreen Bottom")
		(1 "F.Mask" user "Board Geometry/Soldermask Top")
		(3 "B.Mask" user "Board Geometry/Soldermask Bottom")
		(17 "Dwgs.User" user "User.Drawings")
		(19 "Cmts.User" user "User.Comments")
		(21 "Eco1.User" user "User.Eco1")
		(23 "Eco2.User" user "User.Eco2")
		(25 "Edge.Cuts" user "Board Geometry/Outline")
		(27 "Margin" user)
		(31 "F.CrtYd" user "Package Geometry/Place Bound Top")
		(29 "B.CrtYd" user "Package Geometry/Place Bound Bottom")
		(35 "F.Fab" user "Ref Des/Assembly Top")
		(33 "B.Fab" user "Ref Des/Assembly Bottom")
	)
	(footprint ""
		(layer "F.Cu")
		(at 59.832748 -137.438384 90)
		(property "Reference" "TP74"
			(at 0 0 90)
			(layer "F.SilkS")
			(hide yes)
			(effects
				(font
					(size 1.27 1.27)
				)
			)
		)
		(property "Value" "TPAD28-2-GP"
			(at -0.0127 -1.6637 90)
			(unlocked yes)
			(layer "F.Fab")
			(hide yes)
			(effects
				(font
					(size 1.016 1.016)
					(thickness 0.1524)
				)
			)
		)
		(property "Device Type" "TPAD28"
			(at -0.0127 -3.1877 90)
			(unlocked yes)
			(layer "F.Fab")
			(hide yes)
			(effects
				(font
					(size 1.016 1.016)
					(thickness 0.1524)
				)
			)
		)
		(duplicate_pad_numbers_are_jumpers no)
		(fp_poly
			(pts
				(arc
					(start 0 0.3556)
					(mid 0 -0.3556)
					(end 0 0.3556)
				)
			)
			(stroke
				(width 0)
				(type default)
			)
			(fill no)
			(layer "F.CrtYd")
		)
		(fp_poly
			(pts
				(arc
					(start 0 0.6096)
					(mid 0 -0.6096)
					(end 0 0.6096)
				)
			)
			(stroke
				(width 0)
				(type default)
			)
			(fill no)
			(layer "F.Fab")
		)
		(pad "1" smd circle
			(at 0 0 90)
			(size 0.7112 0.7112)
			(layers "F.Cu" "F.Mask" "F.Paste")
			(net "TP_BMC_GPIOI2")
		)
	)
	(footprint ""
		(layer "F.Cu")
		(at 206.629 -81.915 -90)
		(property "Reference" "R570"
			(at 0 0 270)
			(layer "F.SilkS")
			(hide yes)
			(effects
				(font
					(size 1.27 1.27)
				)
			)
		)
		(property "Value" "51R2F-2-GP"
			(at 0.064008 -3.993896 270)
			(unlocked yes)
			(layer "F.Fab")
			(hide yes)
			(effects
				(font
					(size 1.016 1.016)
					(thickness 0.1524)
				)
			)
		)
		(property "Device Type" "R402H16"
			(at 0.064008 -5.517896 270)
			(unlocked yes)
			(layer "F.Fab")
			(hide yes)
			(effects
				(font
					(size 1.016 1.016)
					(thickness 0.1524)
				)
			)
		)
		(duplicate_pad_numbers_are_jumpers no)
		(fp_line
			(start -0.508 -0.9398)
			(end -0.508 0.9398)
			(stroke
				(width 0.1524)
				(type default)
			)
			(layer "F.SilkS")
		)
		(fp_line
			(start 0.508 -0.9398)
			(end -0.508 -0.9398)
			(stroke
				(width 0.1524)
				(type default)
			)
			(layer "F.SilkS")
		)
		(fp_rect
			(start -0.508 0.9398)
			(end 0.508 -0.9398)
			(stroke
				(width 0)
				(type default)
			)
			(fill no)
			(layer "F.CrtYd")
		)
		(fp_rect
			(start -0.508 0.9398)
			(end 0.508 -0.9398)
			(stroke
				(width 0)
				(type default)
			)
			(fill no)
			(layer "F.Fab")
		)
		(pad "1" smd custom
			(at 0 -0.4445 270)
			(size 0.1397 0.1397)
			(layers "F.Cu" "F.Mask" "F.Paste")
			(net "PCIE_COMP_TO_IOM_CLK_2_DN")
			(options
				(clearance outline)
				(anchor circle)
			)
			(primitives
				(gr_poly
					(pts
						(arc
							(start -0.1778 -0.2794)
							(mid -0.249642 -0.249642)
							(end -0.2794 -0.1778)
						)
						(arc
							(start -0.2794 0.1778)
							(mid -0.249642 0.249642)
							(end -0.1778 0.2794)
						)
						(arc
							(start 0.1778 0.2794)
							(mid 0.249642 0.249642)
							(end 0.2794 0.1778)
						)
						(arc
							(start 0.2794 -0.1778)
							(mid 0.249642 -0.249642)
							(end 0.1778 -0.2794)
						)
					)
					(width 0)
					(fill yes)
				)
			)
		)
		(pad "2" smd custom
			(at 0 0.4445 270)
			(size 0.1397 0.1397)
			(layers "F.Cu" "F.Mask" "F.Paste")
			(net "GND")
			(options
				(clearance outline)
				(anchor circle)
			)
			(primitives
				(gr_poly
					(pts
						(arc
							(start -0.1778 -0.2794)
							(mid -0.249642 -0.249642)
							(end -0.2794 -0.1778)
						)
						(arc
							(start -0.2794 0.1778)
							(mid -0.249642 0.249642)
							(end -0.1778 0.2794)
						)
						(arc
							(start 0.1778 0.2794)
							(mid 0.249642 0.249642)
							(end 0.2794 0.1778)
						)
						(arc
							(start 0.2794 -0.1778)
							(mid 0.249642 -0.249642)
							(end 0.1778 -0.2794)
						)
					)
					(width 0)
					(fill yes)
				)
			)
		)
	)
	(footprint ""
		(layer "F.Cu")
		(at 198.501 -88.773 135)
		(property "Reference" "VIA19"
			(at 0 0 135)
			(layer "F.SilkS")
			(hide yes)
			(effects
				(font
					(size 1.27 1.27)
				)
			)
		)
		(property "Value" "85OHM-8L-1D6MM-L16L18-GP"
			(at 4.064105 0.609655 135)
			(unlocked yes)
			(layer "F.Fab")
			(hide yes)
			(effects
				(font
					(size 1.016 1.016)
					(thickness 0.1524)
				)
			)
		)
		(property "Device Type" "VIA-PCIE-4P-368076"
			(at 4.064105 -0.914474 135)
			(unlocked yes)
			(layer "F.Fab")
			(hide yes)
			(effects
				(font
					(size 1.016 1.016)
					(thickness 0.1524)
				)
			)
		)
		(duplicate_pad_numbers_are_jumpers no)
		(fp_poly
			(pts
				(xy -1.841491 -0.381057) (xy 1.841509 -0.381058) (xy 1.841508 0.380942) (xy -1.841491 0.380942)
			)
			(stroke
				(width 0)
				(type default)
			)
			(fill no)
			(layer "F.CrtYd")
		)
		(fp_poly
			(pts
				(xy -1.841491 -0.381057) (xy 1.841509 -0.381058) (xy 1.841508 0.380942) (xy -1.841491 0.380942)
			)
			(stroke
				(width 0)
				(type default)
			)
			(fill no)
			(layer "F.Fab")
		)
		(pad "1" thru_hole circle
			(at -1.460499 0 135)
			(size 0.508 0.508)
			(drill 0.254)
			(layers "*.Cu" "*.Mask")
			(remove_unused_layers no)
			(net "GND")
			(clearance 0.127)
			(thermal_gap 0.127)
		)
		(pad "2" thru_hole circle
			(at -0.4445 0 135)
			(size 0.508 0.508)
			(drill 0.254)
			(layers "*.Cu" "*.Mask")
			(remove_unused_layers no)
			(net "PCIE_COMP_TO_IOM_10_DP")
			(clearance 0.127)
			(thermal_gap 0.127)
		)
		(pad "3" thru_hole circle
			(at 0.4445 0 135)
			(size 0.508 0.508)
			(drill 0.254)
			(layers "*.Cu" "*.Mask")
			(remove_unused_layers no)
			(net "PCIE_COMP_TO_IOM_10_DN")
			(clearance 0.127)
			(thermal_gap 0.127)
		)
		(pad "4" thru_hole circle
			(at 1.460499 0 135)
			(size 0.508 0.508)
			(drill 0.254)
			(layers "*.Cu" "*.Mask")
			(remove_unused_layers no)
			(net "GND")
			(clearance 0.127)
			(thermal_gap 0.127)
		)
	)
	(footprint ""
		(layer "F.Cu")
		(at 112.86109 -8.726678 -90)
		(property "Reference" "C131"
			(at 0 0 270)
			(layer "F.SilkS")
			(hide yes)
			(effects
				(font
					(size 1.27 1.27)
				)
			)
		)
		(property "Value" "SCD01U25V2KX-3GP"
			(at 1.1811 -2.7051 270)
			(unlocked yes)
			(layer "F.Fab")
			(hide yes)
			(effects
				(font
					(size 1.016 1.016)
					(thickness 0.1524)
				)
			)
		)
		(property "Device Type" "C402H22"
			(at 1.1811 -4.2291 270)
			(unlocked yes)
			(layer "F.Fab")
			(hide yes)
			(effects
				(font
					(size 1.016 1.016)
					(thickness 0.1524)
				)
			)
		)
		(duplicate_pad_numbers_are_jumpers no)
		(fp_rect
			(start -0.4318 0.9525)
			(end 0.4318 -0.9525)
			(stroke
				(width 0)
				(type default)
			)
			(fill no)
			(layer "F.CrtYd")
		)
		(fp_rect
			(start -0.4318 0.9525)
			(end 0.4318 -0.9525)
			(stroke
				(width 0)
				(type default)
			)
			(fill no)
			(layer "F.Fab")
		)
		(pad "1" smd custom
			(at 0 -0.4445 270)
			(size 0.1524 0.1524)
			(layers "F.Cu" "F.Mask" "F.Paste")
			(net "MB0_TIME_R")
			(options
				(clearance outline)
				(anchor circle)
			)
			(primitives
				(gr_poly
					(pts
						(arc
							(start 0.3048 -0.2032)
							(mid 0.275042 -0.275042)
							(end 0.2032 -0.3048)
						)
						(arc
							(start -0.2032 -0.3048)
							(mid -0.275042 -0.275042)
							(end -0.3048 -0.2032)
						)
						(arc
							(start -0.3048 0.2032)
							(mid -0.275042 0.275042)
							(end -0.2032 0.3048)
						)
						(arc
							(start 0.2032 0.3048)
							(mid 0.275042 0.275042)
							(end 0.3048 0.2032)
						)
					)
					(width 0)
					(fill yes)
				)
			)
		)
		(pad "2" smd custom
			(at 0 0.4445 270)
			(size 0.1524 0.1524)
			(layers "F.Cu" "F.Mask" "F.Paste")
			(net "AGND_CURRENT_MON")
			(options
				(clearance outline)
				(anchor circle)
			)
			(primitives
				(gr_poly
					(pts
						(arc
							(start 0.3048 -0.2032)
							(mid 0.275042 -0.275042)
							(end 0.2032 -0.3048)
						)
						(arc
							(start -0.2032 -0.3048)
							(mid -0.275042 -0.275042)
							(end -0.3048 -0.2032)
						)
						(arc
							(start -0.3048 0.2032)
							(mid -0.275042 0.275042)
							(end -0.2032 0.3048)
						)
						(arc
							(start 0.2032 0.3048)
							(mid 0.275042 0.275042)
							(end 0.3048 0.2032)
						)
					)
					(width 0)
					(fill yes)
				)
			)
		)
	)
	(footprint ""
		(layer "F.Cu")
		(at 202.8698 -49.9618)
		(property "Reference" "TP141"
			(at 0 0 0)
			(layer "F.SilkS")
			(hide yes)
			(effects
				(font
					(size 1.27 1.27)
				)
			)
		)
		(property "Value" "TPAD28-2-GP"
			(at -0.0127 -1.6637 0)
			(unlocked yes)
			(layer "F.Fab")
			(hide yes)
			(effects
				(font
					(size 1.016 1.016)
					(thickness 0.1524)
				)
			)
		)
		(property "Device Type" "TPAD28"
			(at -0.0127 -3.1877 0)
			(unlocked yes)
			(layer "F.Fab")
			(hide yes)
			(effects
				(font
					(size 1.016 1.016)
					(thickness 0.1524)
				)
			)
		)
		(duplicate_pad_numbers_are_jumpers no)
		(fp_poly
			(pts
				(arc
					(start 0.3556 0)
					(mid -0.3556 0)
					(end 0.3556 0)
				)
			)
			(stroke
				(width 0)
				(type default)
			)
			(fill no)
			(layer "F.CrtYd")
		)
		(fp_poly
			(pts
				(arc
					(start 0.6096 0)
					(mid -0.6096 0)
					(end 0.6096 0)
				)
			)
			(stroke
				(width 0)
				(type default)
			)
			(fill no)
			(layer "F.Fab")
		)
		(pad "1" smd circle
			(at 0 0)
			(size 0.7112 0.7112)
			(layers "F.Cu" "F.Mask" "F.Paste")
			(net "ICE1_TMS")
		)
	)
	(footprint ""
		(layer "F.Cu")
		(at 184.1754 -118.0338 90)
		(property "Reference" "C270"
			(at 0 0 90)
			(layer "F.SilkS")
			(hide yes)
			(effects
				(font
					(size 1.27 1.27)
				)
			)
		)
		(property "Value" "SC10U16V5KX-7-GP-U"
			(at -0.0762 -6.1214 90)
			(unlocked yes)
			(layer "F.Fab")
			(hide yes)
			(effects
				(font
					(size 1.016 1.016)
					(thickness 0.1524)
				)
			)
		)
		(property "Device Type" "C805H58"
			(at -0.0762 -8.1534 90)
			(unlocked yes)
			(layer "F.Fab")
			(hide yes)
			(effects
				(font
					(size 1.016 1.016)
					(thickness 0.1524)
				)
			)
		)
		(duplicate_pad_numbers_are_jumpers no)
		(fp_line
			(start 0.635 0)
			(end -0.635 0)
			(stroke
				(width 0.508)
				(type default)
			)
			(layer "F.SilkS")
		)
		(fp_rect
			(start -0.9652 1.778)
			(end 0.9652 -1.778)
			(stroke
				(width 0)
				(type default)
			)
			(fill no)
			(layer "F.CrtYd")
		)
		(fp_poly
			(pts
				(xy -0.9652 -1.778) (xy 0.9652 -1.778) (xy 0.9652 1.778) (xy -0.9652 1.778)
			)
			(stroke
				(width 0)
				(type default)
			)
			(fill no)
			(layer "F.Fab")
		)
		(pad "1" smd rect
			(at 0 -0.9652 90)
			(size 1.397 1.143)
			(layers "F.Cu" "F.Mask" "F.Paste")
			(net "VT235_VDDH")
		)
		(pad "2" smd rect
			(at 0 0.9652 90)
			(size 1.397 1.143)
			(layers "F.Cu" "F.Mask" "F.Paste")
			(net "GND")
		)
	)
	(footprint ""
		(layer "F.Cu")
		(at 227.925376 -76.972414)
		(property "Reference" "Q14"
			(at 0 0 0)
			(layer "F.SilkS")
			(hide yes)
			(effects
				(font
					(size 1.27 1.27)
				)
			)
		)
		(property "Value" "SSM3K324R-GP"
			(at 0.127 -8.9662 0)
			(unlocked yes)
			(layer "F.Fab")
			(hide yes)
			(effects
				(font
					(size 1.016 1.016)
					(thickness 0.1524)
				)
			)
		)
		(property "Device Type" "SOT23DGS2D4H35"
			(at 0.127 -10.4902 0)
			(unlocked yes)
			(layer "F.Fab")
			(hide yes)
			(effects
				(font
					(size 1.016 1.016)
					(thickness 0.1524)
				)
			)
		)
		(duplicate_pad_numbers_are_jumpers no)
		(fp_line
			(start -1.651 -1.778)
			(end -1.651 1.778)
			(stroke
				(width 0.1524)
				(type default)
			)
			(layer "F.SilkS")
		)
		(fp_line
			(start -1.651 1.778)
			(end 1.651 1.778)
			(stroke
				(width 0.1524)
				(type default)
			)
			(layer "F.SilkS")
		)
		(fp_line
			(start 1.651 -1.778)
			(end -1.651 -1.778)
			(stroke
				(width 0.1524)
				(type default)
			)
			(layer "F.SilkS")
		)
		(fp_line
			(start 1.651 1.778)
			(end 1.651 -1.778)
			(stroke
				(width 0.1524)
				(type default)
			)
			(layer "F.SilkS")
		)
		(fp_poly
			(pts
				(xy -1.778 1.8796) (xy -1.778 -1.8796) (xy 1.778 -1.8796) (xy 1.778 1.8796)
			)
			(stroke
				(width 0)
				(type default)
			)
			(fill no)
			(layer "F.CrtYd")
		)
		(fp_poly
			(pts
				(xy -1.778 1.8796) (xy -1.778 -1.8796) (xy 1.778 -1.8796) (xy 1.778 1.8796)
			)
			(stroke
				(width 0)
				(type default)
			)
			(fill no)
			(layer "F.Fab")
		)
		(pad "D" smd custom
			(at 0 -0.9525)
			(size 0.1905 0.1905)
			(layers "F.Cu" "F.Mask" "F.Paste")
			(net "SYS_ERROR_LED_D")
			(options
				(clearance outline)
				(anchor circle)
			)
			(primitives
				(gr_poly
					(pts
						(arc
							(start -0.1778 0.5715)
							(mid -0.321484 0.511984)
							(end -0.381 0.3683)
						)
						(arc
							(start -0.381 -0.3683)
							(mid -0.321484 -0.511984)
							(end -0.1778 -0.5715)
						)
						(arc
							(start 0.1778 -0.5715)
							(mid 0.321484 -0.511984)
							(end 0.381 -0.3683)
						)
						(arc
							(start 0.381 0.3683)
							(mid 0.321484 0.511984)
							(end 0.1778 0.5715)
						)
					)
					(width 0)
					(fill yes)
				)
			)
		)
		(pad "G" smd custom
			(at -0.98425 0.9525)
			(size 0.1905 0.1905)
			(layers "F.Cu" "F.Mask" "F.Paste")
			(net "SYS_ERR_0")
			(options
				(clearance outline)
				(anchor circle)
			)
			(primitives
				(gr_poly
					(pts
						(arc
							(start -0.1778 0.5715)
							(mid -0.321484 0.511984)
							(end -0.381 0.3683)
						)
						(arc
							(start -0.381 -0.3683)
							(mid -0.321484 -0.511984)
							(end -0.1778 -0.5715)
						)
						(arc
							(start 0.1778 -0.5715)
							(mid 0.321484 -0.511984)
							(end 0.381 -0.3683)
						)
						(arc
							(start 0.381 0.3683)
							(mid 0.321484 0.511984)
							(end 0.1778 0.5715)
						)
					)
					(width 0)
					(fill yes)
				)
			)
		)
		(pad "S" smd custom
			(at 0.98425 0.9525)
			(size 0.1905 0.1905)
			(layers "F.Cu" "F.Mask" "F.Paste")
			(net "GND")
			(options
				(clearance outline)
				(anchor circle)
			)
			(primitives
				(gr_poly
					(pts
						(arc
							(start -0.1778 0.5715)
							(mid -0.321484 0.511984)
							(end -0.381 0.3683)
						)
						(arc
							(start -0.381 -0.3683)
							(mid -0.321484 -0.511984)
							(end -0.1778 -0.5715)
						)
						(arc
							(start 0.1778 -0.5715)
							(mid 0.321484 -0.511984)
							(end 0.381 -0.3683)
						)
						(arc
							(start 0.381 0.3683)
							(mid 0.321484 0.511984)
							(end 0.1778 0.5715)
						)
					)
					(width 0)
					(fill yes)
				)
			)
		)
	)
	(footprint ""
		(layer "F.Cu")
		(at 181.2036 -80.4672)
		(property "Reference" "TP105"
			(at 0 0 0)
			(layer "F.SilkS")
			(hide yes)
			(effects
				(font
					(size 1.27 1.27)
				)
			)
		)
		(property "Value" "TPAD28-2-GP"
			(at -0.0127 -1.6637 0)
			(unlocked yes)
			(layer "F.Fab")
			(hide yes)
			(effects
				(font
					(size 1.016 1.016)
					(thickness 0.1524)
				)
			)
		)
		(property "Device Type" "TPAD28"
			(at -0.0127 -3.1877 0)
			(unlocked yes)
			(layer "F.Fab")
			(hide yes)
			(effects
				(font
					(size 1.016 1.016)
					(thickness 0.1524)
				)
			)
		)
		(duplicate_pad_numbers_are_jumpers no)
		(fp_poly
			(pts
				(arc
					(start 0.3556 0)
					(mid -0.3556 0)
					(end 0.3556 0)
				)
			)
			(stroke
				(width 0)
				(type default)
			)
			(fill no)
			(layer "F.CrtYd")
		)
		(fp_poly
			(pts
				(arc
					(start 0.6096 0)
					(mid -0.6096 0)
					(end 0.6096 0)
				)
			)
			(stroke
				(width 0)
				(type default)
			)
			(fill no)
			(layer "F.Fab")
		)
		(pad "1" smd circle
			(at 0 0)
			(size 0.7112 0.7112)
			(layers "F.Cu" "F.Mask" "F.Paste")
			(net "IOC_GPIO_20")
		)
	)
	(footprint ""
		(layer "F.Cu")
		(at 92.499942 -187.999878)
		(property "Reference" ""
			(at 0 0 0)
			(layer "F.SilkS")
			(hide yes)
			(effects
				(font
					(size 1.27 1.27)
				)
			)
		)
		(property "Value" "*"
			(at -6.38175 0.19685 0)
			(unlocked yes)
			(layer "F.Fab")
			(hide yes)
			(effects
				(font
					(size 1.016 1.016)
					(thickness 0.1524)
				)
			)
		)
		(duplicate_pad_numbers_are_jumpers no)
		(fp_poly
			(pts
				(arc
					(start 5.0673 0)
					(mid -5.0673 0)
					(end 5.0673 0)
				)
			)
			(stroke
				(width 0)
				(type default)
			)
			(fill no)
			(layer "B.CrtYd")
		)
		(fp_poly
			(pts
				(arc
					(start 5.0673 0)
					(mid -5.0673 0)
					(end 5.0673 0)
				)
			)
			(stroke
				(width 0)
				(type default)
			)
			(fill no)
			(layer "F.CrtYd")
		)
		(fp_poly
			(pts
				(arc
					(start 5.0673 0)
					(mid -5.0673 0)
					(end 5.0673 0)
				)
			)
			(stroke
				(width 0)
				(type default)
			)
			(fill no)
			(layer "B.Fab")
		)
		(fp_poly
			(pts
				(arc
					(start 5.0673 0)
					(mid -5.0673 0)
					(end 5.0673 0)
				)
			)
			(stroke
				(width 0)
				(type default)
			)
			(fill no)
			(layer "F.Fab")
		)
		(pad "1" thru_hole circle
			(at 0 0)
			(size 9.525 9.525)
			(drill 3.5052)
			(layers "*.Cu" "*.Mask")
			(remove_unused_layers no)
			(net "Net_8")
			(clearance -2.5019)
			(thermal_gap 0.3048)
			(padstack
				(mode front_inner_back)
				(layer "Inner"
					(shape circle)
					(size 3.9116 3.9116)
					(clearance 0.3048)
				)
				(layer "B.Cu"
					(shape circle)
					(size 9.525 9.525)
					(clearance -2.5019)
				)
			)
		)
	)
)
